# S9S_MB_2U (Grand Teton) — schematic netlist excerpt (pin names and nets, part order shuffled) for the footprints in the layout excerpt that follows; sources: Cadence DE-HDL packaged netlist, KiCad conversion of 03242023_DA0F0TMBIJ0_F0T_Motherboard_J_brd_V01_OCP.brd

J11  SCONN288_ADR50017P130CC  SCONN288_ADR50017-P130CC IO  pkg DDR288S_1-1VXB  page 92
  VIN_BULK0  = P12V_S3_AUX_CPU0_NVDIMM
  RFU0  = TP_CHF_CPU0_DIMM1_FRU_0
  VIN_MGMT  = P3V3_AUX
  HSCL  = I3C_SPD_DDREFGH_CPU0_LVC1_SCL_2
  HSDA  = I3C_SPD_DDREFGH_CPU0_LVC1_SDA
  VSS0  = GND
  DQ0_A  = M_F_CPU0_SA_DQ<0>
  VSS1  = GND
  DQ1_A  = M_F_CPU0_SA_DQ<1>
  VSS2  = GND
  DQS0_A_T  = M_F_CPU0_SA_DQS_DP<0>
  DQS0_A_C  = M_F_CPU0_SA_DQS_DN<0>
  VSS3  = GND
  DQ4_A  = M_F_CPU0_SA_DQ<4>
  VSS4  = GND
  DQ5_A  = M_F_CPU0_SA_DQ<5>
  VSS5  = GND
  DQ8_A  = M_F_CPU0_SA_DQ<8>
  VSS6  = GND
  DQ9_A  = M_F_CPU0_SA_DQ<9>
  VSS7  = GND
  DQS1_A_T  = M_F_CPU0_SA_DQS_DP<1>
  DQS1_A_C  = M_F_CPU0_SA_DQS_DN<1>
  VSS8  = GND
  DQ12_A  = M_F_CPU0_SA_DQ<12>
  VSS9  = GND
  DQ13_A  = M_F_CPU0_SA_DQ<13>
  VSS10  = GND
  DQ16_A  = M_F_CPU0_SA_DQ<16>
  VSS11  = GND
  DQ17_A  = M_F_CPU0_SA_DQ<17>
  VSS12  = GND
  DQS2_A_T  = M_F_CPU0_SA_DQS_DP<2>
  DQS2_A_C  = M_F_CPU0_SA_DQS_DN<2>
  VSS13  = GND
  DQ20_A  = M_F_CPU0_SA_DQ<20>
  VSS14  = GND
  DQ21_A  = M_F_CPU0_SA_DQ<21>
  VSS15  = GND
  DQ24_A  = M_F_CPU0_SA_DQ<24>
  VSS16  = GND
  DQ25_A  = M_F_CPU0_SA_DQ<25>
  VSS17  = GND
  DQS3_A_T  = M_F_CPU0_SA_DQS_DP<3>
  DQS3_A_C  = M_F_CPU0_SA_DQS_DN<3>
  VSS18  = GND
  DQ28_A  = M_F_CPU0_SA_DQ<28>
  VSS19  = GND
  DQ29_A  = M_F_CPU0_SA_DQ<29>
  VSS20  = GND
  CB0_A  = M_F_CPU0_SA_CB<0>
  VSS21  = GND
  CB1_A  = M_F_CPU0_SA_CB<1>
  VSS22  = GND
  DQS4_A_T  = M_F_CPU0_SA_DQS_DP<4>
  DQS4_A_C  = M_F_CPU0_SA_DQS_DN<4>
  VSS23  = GND
  CB4_A  = M_F_CPU0_SA_CB<4>
  VSS24  = GND
  CB5_A  = M_F_CPU0_SA_CB<5>
  VSS25  = GND
  ALERT_N  = M_F_CPU0_ALERT_N
  VSS26  = GND
  CS0_A_N  = M_F_CPU0_SA_CS_N<0>
  VSS27  = GND
  CA0_A  = M_F_CPU0_SA_CA<0>
  VSS28  = GND
  CA2_A  = M_F_CPU0_SA_CA<2>
  VSS29  = GND
  CA4_A  = M_F_CPU0_SA_CA<4>
  VSS30  = GND
  CA6_A  = M_F_CPU0_SA_CA<6>
  VSS31  = GND
  PAR_A  = M_F_CPU0_SA_PAR
  VSS32  = GND
  CA0_B  = M_F_CPU0_SB_CA<0>
  VSS33  = GND
  CA2_B  = M_F_CPU0_SB_CA<2>
  VSS34  = GND
  CA4_B  = M_F_CPU0_SB_CA<4>
  VSS35  = GND
  CA6_B  = M_F_CPU0_SB_CA<6>
  VSS36  = GND
  CS0_B_N  = M_F_CPU0_SB_CS_N<0>
  VSS37  = GND
  \lbd||rsp_a_n\  = M_F_CPU0_SA_RSP<0>
  \lbs||rsp_b_n\  = M_F_CPU0_SB_RSP<0>
  VSS38  = GND
  CB4_B  = M_F_CPU0_SB_CB<4>
  VSS39  = GND
  CB5_B  = M_F_CPU0_SB_CB<5>
  VSS40  = GND
  \dqs9_b_t||tdqs9_b_t||dbi4_b_n\  = M_F_CPU0_SB_DQS_DP<9>
  \dqs9_b_c||tdqs9_b_c\  = M_F_CPU0_SB_DQS_DN<9>
  VSS41  = GND
  CB0_B  = M_F_CPU0_SB_CB<0>
  VSS42  = GND
  CB1_B  = M_F_CPU0_SB_CB<1>
  VSS43  = GND
  DQ0_B  = M_F_CPU0_SB_DQ<0>
  VSS44  = GND
  DQ1_B  = M_F_CPU0_SB_DQ<1>
  VSS45  = GND
  DQS0_B_T  = M_F_CPU0_SB_DQS_DP<0>
  DQS0_B_C  = M_F_CPU0_SB_DQS_DN<0>
  VSS46  = GND
  DQ4_B  = M_F_CPU0_SB_DQ<4>
  VSS47  = GND
  DQ5_B  = M_F_CPU0_SB_DQ<5>
  VSS48  = GND
  DQ8_B  = M_F_CPU0_SB_DQ<8>
  VSS49  = GND
  DQ9_B  = M_F_CPU0_SB_DQ<9>
  VSS50  = GND
  DQS1_B_T  = M_F_CPU0_SB_DQS_DP<1>
  DQS1_B_C  = M_F_CPU0_SB_DQS_DN<1>
  VSS51  = GND
  DQ12_B  = M_F_CPU0_SB_DQ<12>
  VSS52  = GND
  DQ13_B  = M_F_CPU0_SB_DQ<13>
  VSS53  = GND
  DQ16_B  = M_F_CPU0_SB_DQ<16>
  VSS54  = GND
  DQ17_B  = M_F_CPU0_SB_DQ<17>
  VSS55  = GND
  DQS2_B_T  = M_F_CPU0_SB_DQS_DP<2>
  DQS2_B_C  = M_F_CPU0_SB_DQS_DN<2>
  VSS56  = GND
  DQ20_B  = M_F_CPU0_SB_DQ<20>
  VSS57  = GND
  DQ21_B  = M_F_CPU0_SB_DQ<21>
  VSS58  = GND
  DQ24_B  = M_F_CPU0_SB_DQ<24>
  VSS59  = GND
  DQ25_B  = M_F_CPU0_SB_DQ<25>
  VSS60  = GND
  DQS3_B_T  = M_F_CPU0_SB_DQS_DP<3>
  DQS3_B_C  = M_F_CPU0_SB_DQS_DN<3>
  VSS61  = GND
  DQ28_B  = M_F_CPU0_SB_DQ<28>
  VSS62  = GND
  DQ29_B  = M_F_CPU0_SB_DQ<29>
  VSS63  = GND
  RFU1  = TP_CHF_CPU0_DIMM1_FRU_1
  VIN_BULK1  = P12V_S3_AUX_CPU0_NVDIMM
  VIN_BULK2  = P12V_S3_AUX_CPU0_NVDIMM
  \pwr_good||fail_n\  = PWRGD_CHF_CPU0_DIMM1
  HSA  = PD_CHF_CPU0_DIMM1_SAA
  RFU2  = TP_CHF_CPU0_DIMM1_FRU_2
  RFU3  = TP_CHF_CPU0_DIMM1_FRU_3
  VSS64  = GND
  DQ2_A  = M_F_CPU0_SA_DQ<2>
  VSS65  = GND
  DQ3_A  = M_F_CPU0_SA_DQ<3>
  VSS66  = GND
  \dqs5_a_c||tdqs5_a_c||dqs5_a_t||tdqs5_a_t\  = M_F_CPU0_SA_DQS_DN<5>
  \dqs5_a_t||tdqs5_a_t\  = M_F_CPU0_SA_DQS_DP<5>
  VSS67  = GND
  DQ6_A  = M_F_CPU0_SA_DQ<6>
  VSS68  = GND
  DQ7_A  = M_F_CPU0_SA_DQ<7>
  VSS69  = GND
  DQ10_A  = M_F_CPU0_SA_DQ<10>
  VSS70  = GND
  DQ11_A  = M_F_CPU0_SA_DQ<11>
  VSS71  = GND
  \dqs6_a_c||tdqs6_a_c||dqs6_a_t||tdqs6_a_t\  = M_F_CPU0_SA_DQS_DN<6>
  \dqs6_a_t||tdqs6_a_t\  = M_F_CPU0_SA_DQS_DP<6>
  VSS72  = GND
  DQ14_A  = M_F_CPU0_SA_DQ<14>
  VSS73  = GND
  DQ15_A  = M_F_CPU0_SA_DQ<15>
  VSS74  = GND
  DQ18_A  = M_F_CPU0_SA_DQ<18>
  VSS75  = GND
  DQ19_A  = M_F_CPU0_SA_DQ<19>
  VSS76  = GND
  \dqs7_a_c||tdqs7_a_c\  = M_F_CPU0_SA_DQS_DN<7>
  \dqs7_a_t||tdqs7_a_t\  = M_F_CPU0_SA_DQS_DP<7>
  VSS77  = GND
  DQ22_A  = M_F_CPU0_SA_DQ<22>
  VSS78  = GND
  DQ23_A  = M_F_CPU0_SA_DQ<23>
  VSS79  = GND
  DQ26_A  = M_F_CPU0_SA_DQ<26>
  VSS80  = GND
  DQ27_A  = M_F_CPU0_SA_DQ<27>
  VSS81  = GND
  \dqs8_a_c||tdqs8_a_c\  = M_F_CPU0_SA_DQS_DN<8>
  \dqs8_a_t||tdqs8_a_t\  = M_F_CPU0_SA_DQS_DP<8>
  VSS82  = GND
  DQ30_A  = M_F_CPU0_SA_DQ<30>
  VSS83  = GND
  DQ31_A  = M_F_CPU0_SA_DQ<31>
  VSS84  = GND
  CB2_A  = M_F_CPU0_SA_CB<2>
  VSS85  = GND
  CB3_A  = M_F_CPU0_SA_CB<3>
  VSS86  = GND
  \dqs9_a_c||tdqs9_a_c\  = M_F_CPU0_SA_DQS_DN<9>
  \dqs9_a_t||tdqs9_a_t\  = M_F_CPU0_SA_DQS_DP<9>
  VSS87  = GND
  CB6_A  = M_F_CPU0_SA_CB<6>
  VSS88  = GND
  CB7_A  = M_F_CPU0_SA_CB<7>
  VSS89  = GND
  RESET_N  = RST_M_EF_CPU0_FPGA_N
  VSS90  = GND
  CS1_A_N  = M_F_CPU0_SA_CS_N<1>
  VSS91  = GND
  CA1_A  = M_F_CPU0_SA_CA<1>
  VSS92  = GND
  CA3_A  = M_F_CPU0_SA_CA<3>
  VSS93  = GND
  CA5_A  = M_F_CPU0_SA_CA<5>
  VSS94  = GND
  CK_T  = M_F_CPU0_CLK_DP<0>
  CK_C  = M_F_CPU0_CLK_DN<0>
  VSS95  = GND
  RFU4  = TP_CHF_CPU0_DIMM1_FRU_4
  CA1_B  = M_F_CPU0_SB_CA<1>
  VSS96  = GND
  CA3_B  = M_F_CPU0_SB_CA<3>
  VSS97  = GND
  CA5_B  = M_F_CPU0_SB_CA<5>
  VSS98  = GND
  PAR_B  = M_F_CPU0_SB_PAR
  VSS99  = GND
  CS1_B_N  = M_F_CPU0_SB_CS_N<1>
  VSS100  = GND
  RFU5  = TP_CHF_CPU0_DIMM1_FRU_5
  RFU6  = TP_CHF_CPU0_DIMM1_FRU_6
  VSS101  = GND
  CB6_B  = M_F_CPU0_SB_CB<6>
  VSS102  = GND
  CB7_B  = M_F_CPU0_SB_CB<7>
  VSS103  = GND
  DQS4_B_C  = M_F_CPU0_SB_DQS_DN<4>
  DQS4_B_T  = M_F_CPU0_SB_DQS_DP<4>
  VSS104  = GND
  CB2_B  = M_F_CPU0_SB_CB<2>
  VSS105  = GND
  CB3_B  = M_F_CPU0_SB_CB<3>
  VSS106  = GND
  DQ2_B  = M_F_CPU0_SB_DQ<2>
  VSS107  = GND
  DQ3_B  = M_F_CPU0_SB_DQ<3>
  VSS108  = GND
  \dqs5_b_c||tdqs5_b_c\  = M_F_CPU0_SB_DQS_DN<5>
  \dqs5_b_t||tdqs5_b_t\  = M_F_CPU0_SB_DQS_DP<5>
  VSS109  = GND
  DQ6_B  = M_F_CPU0_SB_DQ<6>
  VSS110  = GND
  DQ7_B  = M_F_CPU0_SB_DQ<7>
  VSS111  = GND
  DQ10_B  = M_F_CPU0_SB_DQ<10>
  VSS112  = GND
  DQ11_B  = M_F_CPU0_SB_DQ<11>
  VSS113  = GND
  \dqs6_b_c||tdqs6_b_c\  = M_F_CPU0_SB_DQS_DN<6>
  \dqs6_b_t||tdqs6_b_t\  = M_F_CPU0_SB_DQS_DP<6>
  VSS114  = GND
  DQ14_B  = M_F_CPU0_SB_DQ<14>
  VSS115  = GND
  DQ15_B  = M_F_CPU0_SB_DQ<15>
  VSS116  = GND
  DQ18_B  = M_F_CPU0_SB_DQ<18>
  VSS117  = GND
  DQ19_B  = M_F_CPU0_SB_DQ<19>
  VSS118  = GND
  \dqs7_b_c||tdqs7_b_c\  = M_F_CPU0_SB_DQS_DN<7>
  \dqs7_b_t||tdqs7_b_t\  = M_F_CPU0_SB_DQS_DP<7>
  VSS119  = GND
  DQ22_B  = M_F_CPU0_SB_DQ<22>
  VSS120  = GND
  DQ23_B  = M_F_CPU0_SB_DQ<23>
  VSS121  = GND
  DQ26_B  = M_F_CPU0_SB_DQ<26>
  VSS122  = GND
  DQ27_B  = M_F_CPU0_SB_DQ<27>
  VSS123  = GND
  \dqs8_b_c||tdqs8_b_c\  = M_F_CPU0_SB_DQS_DN<8>
  \dqs8_b_t||tdqs8_b_t\  = M_F_CPU0_SB_DQS_DP<8>
  VSS124  = GND
  DQ30_B  = M_F_CPU0_SB_DQ<30>
  VSS125  = GND
  DQ31_B  = M_F_CPU0_SB_DQ<31>
  VSS126  = GND
  G1  = GND
  G2  = GND
  G3  = GND

(kicad_pcb
	(version 20260206)
	(generator "pcbnew")
	(generator_version "10.0")
	(general
		(thickness 1.6)
		(legacy_teardrops no)
	)
	(paper "A4")
	(title_block
		(title "03242023_DA0F0TMBIJ0_F0T_Motherboard_J_brd_V01_OCP.brd")
		(comment 1 "Grand Teton / footprint 1952 of 6105 (J11), pads 275-291 of 291")
	)
	(layers
		(0 "F.Cu" signal "TOP")
		(4 "In1.Cu" signal "GND")
		(6 "In2.Cu" signal "IN1")
		(8 "In3.Cu" signal "GND1")
		(10 "In4.Cu" signal "IN2")
		(12 "In5.Cu" signal "GND2")
		(14 "In6.Cu" signal "IN3")
		(16 "In7.Cu" signal "GND3")
		(18 "In8.Cu" signal "VCC")
		(20 "In9.Cu" signal "VCC1")
		(22 "In10.Cu" signal "GND4")
		(24 "In11.Cu" signal "IN4")
		(26 "In12.Cu" signal "GND5")
		(28 "In13.Cu" signal "IN5")
		(30 "In14.Cu" signal "GND6")
		(32 "In15.Cu" signal "IN6")
		(34 "In16.Cu" signal "GND7")
		(2 "B.Cu" signal "BOTTOM")
		(9 "F.Adhes" user "F.Adhesive")
		(11 "B.Adhes" user "B.Adhesive")
		(13 "F.Paste" user "Package Geometry/Pastemask Top")
		(15 "B.Paste" user "Package Geometry/Pastemask Bottom")
		(5 "F.SilkS" user "Ref Des/Silkscreen Top")
		(7 "B.SilkS" user "Ref Des/Silkscreen Bottom")
		(1 "F.Mask" user "Board Geometry/Soldermask Top")
		(3 "B.Mask" user "Board Geometry/Soldermask Bottom")
		(17 "Dwgs.User" user "User.Drawings")
		(19 "Cmts.User" user "User.Comments")
		(21 "Eco1.User" user "User.Eco1")
		(23 "Eco2.User" user "User.Eco2")
		(25 "Edge.Cuts" user "Board Geometry/Outline")
		(27 "Margin" user)
		(31 "F.CrtYd" user "Package Geometry/Place Bound Top")
		(29 "B.CrtYd" user "Package Geometry/Place Bound Bottom")
		(35 "F.Fab" user "Ref Des/Assembly Top")
		(33 "B.Fab" user "Ref Des/Assembly Bottom")
	)
	(footprint ""
		(layer "F.Cu")
		(at 431.434748 -258.091686)
		(property "Reference" "J11"
			(at -3.683 -81.702148 0)
			(unlocked yes)
			(layer "F.SilkS")
			(effects
				(font
					(size 0.7874 0.5842)
					(thickness 0.1524)
				)
				(justify left)
			)
		)
		(property "Value" ""
			(at 0 0 0)
			(layer "F.Fab")
			(effects
				(font
					(size 1.27 1.27)
				)
			)
		)
		(duplicate_pad_numbers_are_jumpers no)
		(pad "275" smd rect
			(at 2.050034 52.274978 270)
			(size 0.519938 1.4986)
			(layers "F.Cu" "F.Mask" "F.Paste")
			(net "GND")
		)
		(pad "276" smd rect
			(at 2.050034 53.125116 270)
			(size 0.519938 1.4986)
			(layers "F.Cu" "F.Mask" "F.Paste")
			(net "M_F_CPU0_SB_DQ<23>")
		)
		(pad "277" smd rect
			(at 2.050034 53.975 270)
			(size 0.519938 1.4986)
			(layers "F.Cu" "F.Mask" "F.Paste")
			(net "GND")
		)
		(pad "278" smd rect
			(at 2.050034 54.824884 270)
			(size 0.519938 1.4986)
			(layers "F.Cu" "F.Mask" "F.Paste")
			(net "M_F_CPU0_SB_DQ<26>")
		)
		(pad "279" smd rect
			(at 2.050034 55.675022 270)
			(size 0.519938 1.4986)
			(layers "F.Cu" "F.Mask" "F.Paste")
			(net "GND")
		)
		(pad "280" smd rect
			(at 2.050034 56.524906 270)
			(size 0.519938 1.4986)
			(layers "F.Cu" "F.Mask" "F.Paste")
			(net "M_F_CPU0_SB_DQ<27>")
		)
		(pad "281" smd rect
			(at 2.050034 57.375044 270)
			(size 0.519938 1.4986)
			(layers "F.Cu" "F.Mask" "F.Paste")
			(net "GND")
		)
		(pad "282" smd rect
			(at 2.050034 58.224928 270)
			(size 0.519938 1.4986)
			(layers "F.Cu" "F.Mask" "F.Paste")
			(net "M_F_CPU0_SB_DQS_DN<8>")
		)
		(pad "283" smd rect
			(at 2.050034 59.075066 270)
			(size 0.519938 1.4986)
			(layers "F.Cu" "F.Mask" "F.Paste")
			(net "M_F_CPU0_SB_DQS_DP<8>")
		)
		(pad "284" smd rect
			(at 2.050034 59.92495 270)
			(size 0.519938 1.4986)
			(layers "F.Cu" "F.Mask" "F.Paste")
			(net "GND")
		)
		(pad "285" smd rect
			(at 2.050034 60.775088 270)
			(size 0.519938 1.4986)
			(layers "F.Cu" "F.Mask" "F.Paste")
			(net "M_F_CPU0_SB_DQ<30>")
		)
		(pad "286" smd rect
			(at 2.050034 61.624972 270)
			(size 0.519938 1.4986)
			(layers "F.Cu" "F.Mask" "F.Paste")
			(net "GND")
		)
		(pad "287" smd rect
			(at 2.050034 62.47511 270)
			(size 0.519938 1.4986)
			(layers "F.Cu" "F.Mask" "F.Paste")
			(net "M_F_CPU0_SB_DQ<31>")
		)
		(pad "288" smd rect
			(at 2.050034 63.324994 270)
			(size 0.519938 1.4986)
			(layers "F.Cu" "F.Mask" "F.Paste")
			(net "GND")
		)
		(pad "G1" thru_hole oval
			(at 0 -68.97497)
			(size 2.8194 1.5748)
			(drill oval 2.4384 1.1938)
			(layers "*.Cu" "*.Mask")
			(remove_unused_layers no)
			(net "GND")
			(clearance 0.127)
			(thermal_gap 0.127)
		)
		(pad "G2" thru_hole oval
			(at 0 3.875024)
			(size 2.8194 1.5748)
			(drill oval 2.4384 1.1938)
			(layers "*.Cu" "*.Mask")
			(remove_unused_layers no)
			(net "GND")
			(clearance 0.127)
			(thermal_gap 0.127)
		)
		(pad "G3" thru_hole oval
			(at 0 68.97497)
			(size 2.8194 1.5748)
			(drill oval 2.4384 1.1938)
			(layers "*.Cu" "*.Mask")
			(remove_unused_layers no)
			(net "GND")
			(clearance 0.127)
			(thermal_gap 0.127)
		)
	)
)
